# S9S_MB_2U (Grand Teton) — schematic netlist excerpt (pin names and nets, part order shuffled) for the footprints in the layout excerpt that follows; sources: Cadence DE-HDL packaged netlist, KiCad conversion of 03242023_DA0F0TMBIJ0_F0T_Motherboard_J_brd_V01_OCP.brd

R3195  Q_RES  22 1% CHIP  pkg 0402LF  page 207 : A = CLK_100M_OCP_V3_2_A_R_DN ; B = CLK_100M_OCP_V3_2_A_DN
C1521  Q_CAP_DIFFBUS  DIFF BUS_0.22UF 6.3V 20% X6S  pkg C0201  page 177 : \1\ = P5E_CPU1_PE3_TX_C_DP<13> ; \2\ = P5E_CPU1_PE3_TX_DP<13>
R937  Q_RES  10K 1% CHIP  pkg 0402LF  page 128 : A = RST_CPU1_DRAM_EF_N ; B = GND

(kicad_pcb
	(version 20260206)
	(generator "pcbnew")
	(generator_version "10.0")
	(general
		(thickness 1.6)
		(legacy_teardrops no)
	)
	(paper "A4")
	(title_block
		(title "03242023_DA0F0TMBIJ0_F0T_Motherboard_J_brd_V01_OCP.brd")
		(comment 1 "Grand Teton / footprints 3282-3284 of 6105")
	)
	(layers
		(0 "F.Cu" signal "TOP")
		(4 "In1.Cu" signal "GND")
		(6 "In2.Cu" signal "IN1")
		(8 "In3.Cu" signal "GND1")
		(10 "In4.Cu" signal "IN2")
		(12 "In5.Cu" signal "GND2")
		(14 "In6.Cu" signal "IN3")
		(16 "In7.Cu" signal "GND3")
		(18 "In8.Cu" signal "VCC")
		(20 "In9.Cu" signal "VCC1")
		(22 "In10.Cu" signal "GND4")
		(24 "In11.Cu" signal "IN4")
		(26 "In12.Cu" signal "GND5")
		(28 "In13.Cu" signal "IN5")
		(30 "In14.Cu" signal "GND6")
		(32 "In15.Cu" signal "IN6")
		(34 "In16.Cu" signal "GND7")
		(2 "B.Cu" signal "BOTTOM")
		(9 "F.Adhes" user "F.Adhesive")
		(11 "B.Adhes" user "B.Adhesive")
		(13 "F.Paste" user "Package Geometry/Pastemask Top")
		(15 "B.Paste" user "Package Geometry/Pastemask Bottom")
		(5 "F.SilkS" user "Ref Des/Silkscreen Top")
		(7 "B.SilkS" user "Ref Des/Silkscreen Bottom")
		(1 "F.Mask" user "Board Geometry/Soldermask Top")
		(3 "B.Mask" user "Board Geometry/Soldermask Bottom")
		(17 "Dwgs.User" user "User.Drawings")
		(19 "Cmts.User" user "User.Comments")
		(21 "Eco1.User" user "User.Eco1")
		(23 "Eco2.User" user "User.Eco2")
		(25 "Edge.Cuts" user "Board Geometry/Outline")
		(27 "Margin" user)
		(31 "F.CrtYd" user "Package Geometry/Place Bound Top")
		(29 "B.CrtYd" user "Package Geometry/Place Bound Bottom")
		(35 "F.Fab" user "Ref Des/Assembly Top")
		(33 "B.Fab" user "Ref Des/Assembly Bottom")
	)
	(footprint ""
		(layer "F.Cu")
		(at 125.264926 -122.096784 90)
		(property "Reference" "R937"
			(at 0 0 90)
			(layer "F.SilkS")
			(hide yes)
			(effects
				(font
					(size 1.27 1.27)
				)
			)
		)
		(property "Value" ""
			(at 0 0 90)
			(layer "F.Fab")
			(effects
				(font
					(size 1.27 1.27)
				)
			)
		)
		(duplicate_pad_numbers_are_jumpers no)
		(fp_line
			(start 0.7874 -0.4064)
			(end 0.7874 0.4064)
			(stroke
				(width 0.1524)
				(type default)
			)
			(layer "F.SilkS")
		)
		(fp_line
			(start -0.7874 -0.4064)
			(end 0.7874 -0.4064)
			(stroke
				(width 0.1524)
				(type default)
			)
			(layer "F.SilkS")
		)
		(fp_line
			(start 0.7874 0.4064)
			(end -0.7874 0.4064)
			(stroke
				(width 0.1524)
				(type default)
			)
			(layer "F.SilkS")
		)
		(fp_line
			(start -0.7874 0.4064)
			(end -0.7874 -0.4064)
			(stroke
				(width 0.1524)
				(type default)
			)
			(layer "F.SilkS")
		)
		(fp_line
			(start -0.12065 -0.305054)
			(end -0.12065 -0.2794)
			(stroke
				(width 0.1)
				(type default)
			)
			(layer "F.Fab")
		)
		(fp_line
			(start -0.67945 -0.305054)
			(end -0.12065 -0.305054)
			(stroke
				(width 0.1)
				(type default)
			)
			(layer "F.Fab")
		)
		(fp_line
			(start 0.67945 -0.3048)
			(end 0.67945 0.3048)
			(stroke
				(width 0.1)
				(type default)
			)
			(layer "F.Fab")
		)
		(fp_line
			(start 0.12065 -0.3048)
			(end 0.67945 -0.3048)
			(stroke
				(width 0.1)
				(type default)
			)
			(layer "F.Fab")
		)
		(fp_line
			(start 0.12065 -0.2794)
			(end 0.12065 -0.3048)
			(stroke
				(width 0.1)
				(type default)
			)
			(layer "F.Fab")
		)
		(fp_line
			(start -0.12065 -0.2794)
			(end 0.12065 -0.2794)
			(stroke
				(width 0.1)
				(type default)
			)
			(layer "F.Fab")
		)
		(fp_line
			(start 0.120396 0.2794)
			(end -0.12065 0.2794)
			(stroke
				(width 0.1)
				(type default)
			)
			(layer "F.Fab")
		)
		(fp_line
			(start -0.12065 0.2794)
			(end -0.12065 0.3048)
			(stroke
				(width 0.1)
				(type default)
			)
			(layer "F.Fab")
		)
		(fp_line
			(start 0.67945 0.3048)
			(end 0.120396 0.3048)
			(stroke
				(width 0.1)
				(type default)
			)
			(layer "F.Fab")
		)
		(fp_line
			(start 0.120396 0.3048)
			(end 0.120396 0.2794)
			(stroke
				(width 0.1)
				(type default)
			)
			(layer "F.Fab")
		)
		(fp_line
			(start -0.12065 0.3048)
			(end -0.67945 0.3048)
			(stroke
				(width 0.1)
				(type default)
			)
			(layer "F.Fab")
		)
		(fp_line
			(start -0.67945 0.3048)
			(end -0.67945 -0.305054)
			(stroke
				(width 0.1)
				(type default)
			)
			(layer "F.Fab")
		)
		(pad "1" smd circle
			(at -0.40005 0 90)
			(size 0 0)
			(layers "F.Cu" "F.Mask" "F.Paste")
			(net "RST_CPU1_DRAM_EF_N")
		)
		(pad "2" smd circle
			(at 0.40005 0 90)
			(size 0 0)
			(layers "F.Cu" "F.Mask" "F.Paste")
			(net "GND")
		)
	)
	(footprint ""
		(layer "F.Cu")
		(at 128.516634 -408.517344 -90)
		(property "Reference" "C1521"
			(at 0 0 270)
			(layer "F.SilkS")
			(hide yes)
			(effects
				(font
					(size 1.27 1.27)
				)
			)
		)
		(property "Value" ""
			(at 0 0 270)
			(layer "F.Fab")
			(effects
				(font
					(size 1.27 1.27)
				)
			)
		)
		(duplicate_pad_numbers_are_jumpers no)
		(fp_line
			(start -0.299974 0.150114)
			(end -0.299974 -0.150114)
			(stroke
				(width 0.1)
				(type default)
			)
			(layer "F.Fab")
		)
		(fp_line
			(start 0.299974 0.150114)
			(end -0.299974 0.150114)
			(stroke
				(width 0.1)
				(type default)
			)
			(layer "F.Fab")
		)
		(fp_line
			(start -0.299974 -0.150114)
			(end 0.299974 -0.150114)
			(stroke
				(width 0.1)
				(type default)
			)
			(layer "F.Fab")
		)
		(fp_line
			(start 0.299974 -0.150114)
			(end 0.299974 0.150114)
			(stroke
				(width 0.1)
				(type default)
			)
			(layer "F.Fab")
		)
		(pad "1" smd rect
			(at -0.2667 0 270)
			(size 0.3048 0.381)
			(layers "F.Cu" "F.Mask" "F.Paste")
			(net "P5E_CPU1_PE3_TX_C_DP<13>")
		)
		(pad "2" smd rect
			(at 0.2667 0 270)
			(size 0.3048 0.381)
			(layers "F.Cu" "F.Mask" "F.Paste")
			(net "P5E_CPU1_PE3_TX_DP<13>")
		)
	)
	(footprint ""
		(layer "F.Cu")
		(at 234.885738 -119.183658 -90)
		(property "Reference" "R3195"
			(at 0 0 270)
			(layer "F.SilkS")
			(hide yes)
			(effects
				(font
					(size 1.27 1.27)
				)
			)
		)
		(property "Value" ""
			(at 0 0 270)
			(layer "F.Fab")
			(effects
				(font
					(size 1.27 1.27)
				)
			)
		)
		(duplicate_pad_numbers_are_jumpers no)
		(fp_line
			(start 0.410718 0.4064)
			(end -0.363982 0.4064)
			(stroke
				(width 0.1524)
				(type default)
			)
			(layer "F.SilkS")
		)
		(fp_line
			(start -0.7874 0.105918)
			(end -0.7874 -0.4064)
			(stroke
				(width 0.1524)
				(type default)
			)
			(layer "F.SilkS")
		)
		(fp_line
			(start -0.7874 -0.4064)
			(end 0.7874 -0.4064)
			(stroke
				(width 0.1524)
				(type default)
			)
			(layer "F.SilkS")
		)
		(fp_line
			(start 0.7874 -0.4064)
			(end 0.7874 0.123698)
			(stroke
				(width 0.1524)
				(type default)
			)
			(layer "F.SilkS")
		)
		(fp_line
			(start -0.67945 0.3048)
			(end -0.67945 -0.305054)
			(stroke
				(width 0.1)
				(type default)
			)
			(layer "F.Fab")
		)
		(fp_line
			(start -0.12065 0.3048)
			(end -0.67945 0.3048)
			(stroke
				(width 0.1)
				(type default)
			)
			(layer "F.Fab")
		)
		(fp_line
			(start 0.120396 0.3048)
			(end 0.120396 0.2794)
			(stroke
				(width 0.1)
				(type default)
			)
			(layer "F.Fab")
		)
		(fp_line
			(start 0.67945 0.3048)
			(end 0.120396 0.3048)
			(stroke
				(width 0.1)
				(type default)
			)
			(layer "F.Fab")
		)
		(fp_line
			(start -0.12065 0.2794)
			(end -0.12065 0.3048)
			(stroke
				(width 0.1)
				(type default)
			)
			(layer "F.Fab")
		)
		(fp_line
			(start 0.120396 0.2794)
			(end -0.12065 0.2794)
			(stroke
				(width 0.1)
				(type default)
			)
			(layer "F.Fab")
		)
		(fp_line
			(start -0.12065 -0.2794)
			(end 0.12065 -0.2794)
			(stroke
				(width 0.1)
				(type default)
			)
			(layer "F.Fab")
		)
		(fp_line
			(start 0.12065 -0.2794)
			(end 0.12065 -0.3048)
			(stroke
				(width 0.1)
				(type default)
			)
			(layer "F.Fab")
		)
		(fp_line
			(start 0.12065 -0.3048)
			(end 0.67945 -0.3048)
			(stroke
				(width 0.1)
				(type default)
			)
			(layer "F.Fab")
		)
		(fp_line
			(start 0.67945 -0.3048)
			(end 0.67945 0.3048)
			(stroke
				(width 0.1)
				(type default)
			)
			(layer "F.Fab")
		)
		(fp_line
			(start -0.67945 -0.305054)
			(end -0.12065 -0.305054)
			(stroke
				(width 0.1)
				(type default)
			)
			(layer "F.Fab")
		)
		(fp_line
			(start -0.12065 -0.305054)
			(end -0.12065 -0.2794)
			(stroke
				(width 0.1)
				(type default)
			)
			(layer "F.Fab")
		)
		(pad "1" smd circle
			(at -0.40005 0 270)
			(size 0 0)
			(layers "F.Cu" "F.Mask" "F.Paste")
			(net "CLK_100M_OCP_V3_2_A_R_DN")
		)
		(pad "2" smd circle
			(at 0.40005 0 270)
			(size 0 0)
			(layers "F.Cu" "F.Mask" "F.Paste")
			(net "CLK_100M_OCP_V3_2_A_DN")
		)
	)
)
